(kicad_pcb
	(version 20260206)
	(generator "pcbnew")
	(generator_version "10.0")
	(general
		(thickness 1.6)
		(legacy_teardrops no)
	)
	(paper "A4")
	(title_block
		(title "04192023_DAF0TMB3IC0_F0TG_MB_C_brd_V02_OCP.brd")
		(comment 1 "Grand Teton / footprints 4175-4180 of 8354")
	)
	(layers
		(0 "F.Cu" signal "TOP")
		(4 "In1.Cu" signal "GND")
		(6 "In2.Cu" signal "IN1")
		(8 "In3.Cu" signal "GND1")
		(10 "In4.Cu" signal "IN2")
		(12 "In5.Cu" signal "GND2")
		(14 "In6.Cu" signal "IN3")
		(16 "In7.Cu" signal "GND3")
		(18 "In8.Cu" signal "VCC")
		(20 "In9.Cu" signal "VCC1")
		(22 "In10.Cu" signal "GND4")
		(24 "In11.Cu" signal "IN4")
		(26 "In12.Cu" signal "GND5")
		(28 "In13.Cu" signal "IN5")
		(30 "In14.Cu" signal "GND6")
		(32 "In15.Cu" signal "IN6")
		(34 "In16.Cu" signal "GND7")
		(2 "B.Cu" signal "BOTTOM")
		(9 "F.Adhes" user "F.Adhesive")
		(11 "B.Adhes" user "B.Adhesive")
		(13 "F.Paste" user "Package Geometry/Pastemask Top")
		(15 "B.Paste" user "Package Geometry/Pastemask Bottom")
		(5 "F.SilkS" user "Ref Des/Silkscreen Top")
		(7 "B.SilkS" user "Ref Des/Silkscreen Bottom")
		(1 "F.Mask" user "Board Geometry/Soldermask Top")
		(3 "B.Mask" user "Board Geometry/Soldermask Bottom")
		(17 "Dwgs.User" user "User.Drawings")
		(19 "Cmts.User" user "User.Comments")
		(21 "Eco1.User" user "User.Eco1")
		(23 "Eco2.User" user "User.Eco2")
		(25 "Edge.Cuts" user "Board Geometry/Outline")
		(27 "Margin" user)
		(31 "F.CrtYd" user "Package Geometry/Place Bound Top")
		(29 "B.CrtYd" user "Package Geometry/Place Bound Bottom")
		(35 "F.Fab" user "Ref Des/Assembly Top")
		(33 "B.Fab" user "Ref Des/Assembly Bottom")
	)
	(footprint ""
		(layer "F.Cu")
		(at 251.35967 -45.987462 -90)
		(property "Reference" "PC2211"
			(at 0 0 270)
			(layer "F.SilkS")
			(hide yes)
			(effects
				(font
					(size 1.27 1.27)
				)
			)
		)
		(property "Value" ""
			(at 0 0 270)
			(layer "F.Fab")
			(effects
				(font
					(size 1.27 1.27)
				)
			)
		)
		(duplicate_pad_numbers_are_jumpers no)
		(fp_line
			(start -0.7874 0.4064)
			(end -0.7874 -0.4064)
			(stroke
				(width 0.1524)
				(type default)
			)
			(layer "F.SilkS")
		)
		(fp_line
			(start 0.7874 0.4064)
			(end -0.7874 0.4064)
			(stroke
				(width 0.1524)
				(type default)
			)
			(layer "F.SilkS")
		)
		(fp_line
			(start -0.7874 -0.4064)
			(end 0.7874 -0.4064)
			(stroke
				(width 0.1524)
				(type default)
			)
			(layer "F.SilkS")
		)
		(fp_line
			(start 0.7874 -0.4064)
			(end 0.7874 0.4064)
			(stroke
				(width 0.1524)
				(type default)
			)
			(layer "F.SilkS")
		)
		(fp_line
			(start -0.67945 0.3048)
			(end -0.67945 -0.305054)
			(stroke
				(width 0.1)
				(type default)
			)
			(layer "F.Fab")
		)
		(fp_line
			(start -0.12065 0.3048)
			(end -0.67945 0.3048)
			(stroke
				(width 0.1)
				(type default)
			)
			(layer "F.Fab")
		)
		(fp_line
			(start 0.120396 0.3048)
			(end 0.120396 0.2794)
			(stroke
				(width 0.1)
				(type default)
			)
			(layer "F.Fab")
		)
		(fp_line
			(start 0.67945 0.3048)
			(end 0.120396 0.3048)
			(stroke
				(width 0.1)
				(type default)
			)
			(layer "F.Fab")
		)
		(fp_line
			(start -0.12065 0.2794)
			(end -0.12065 0.3048)
			(stroke
				(width 0.1)
				(type default)
			)
			(layer "F.Fab")
		)
		(fp_line
			(start 0.120396 0.2794)
			(end -0.12065 0.2794)
			(stroke
				(width 0.1)
				(type default)
			)
			(layer "F.Fab")
		)
		(fp_line
			(start -0.12065 -0.2794)
			(end 0.12065 -0.2794)
			(stroke
				(width 0.1)
				(type default)
			)
			(layer "F.Fab")
		)
		(fp_line
			(start 0.12065 -0.2794)
			(end 0.12065 -0.3048)
			(stroke
				(width 0.1)
				(type default)
			)
			(layer "F.Fab")
		)
		(fp_line
			(start 0.12065 -0.3048)
			(end 0.67945 -0.3048)
			(stroke
				(width 0.1)
				(type default)
			)
			(layer "F.Fab")
		)
		(fp_line
			(start 0.67945 -0.3048)
			(end 0.67945 0.3048)
			(stroke
				(width 0.1)
				(type default)
			)
			(layer "F.Fab")
		)
		(fp_line
			(start -0.67945 -0.305054)
			(end -0.12065 -0.305054)
			(stroke
				(width 0.1)
				(type default)
			)
			(layer "F.Fab")
		)
		(fp_line
			(start -0.12065 -0.305054)
			(end -0.12065 -0.2794)
			(stroke
				(width 0.1)
				(type default)
			)
			(layer "F.Fab")
		)
		(pad "1" smd circle
			(at -0.40005 0 270)
			(size 0 0)
			(layers "F.Cu" "F.Mask" "F.Paste")
			(net "GND")
		)
		(pad "2" smd circle
			(at 0.40005 0 270)
			(size 0 0)
			(layers "F.Cu" "F.Mask" "F.Paste")
			(net "P12V_E1S_REG_0")
		)
	)
	(footprint ""
		(layer "F.Cu")
		(at 413.928306 -133.66242)
		(property "Reference" "PC1850"
			(at 0 0 0)
			(layer "F.SilkS")
			(hide yes)
			(effects
				(font
					(size 1.27 1.27)
				)
			)
		)
		(property "Value" ""
			(at 0 0 0)
			(layer "F.Fab")
			(effects
				(font
					(size 1.27 1.27)
				)
			)
		)
		(duplicate_pad_numbers_are_jumpers no)
		(fp_line
			(start -1.524 -0.762)
			(end 1.524 -0.762)
			(stroke
				(width 0.1524)
				(type default)
			)
			(layer "F.SilkS")
		)
		(fp_line
			(start -1.524 0.762)
			(end -1.524 -0.762)
			(stroke
				(width 0.1524)
				(type default)
			)
			(layer "F.SilkS")
		)
		(fp_line
			(start 1.524 -0.762)
			(end 1.524 0.762)
			(stroke
				(width 0.1524)
				(type default)
			)
			(layer "F.SilkS")
		)
		(fp_line
			(start 1.524 0.762)
			(end -1.524 0.762)
			(stroke
				(width 0.1524)
				(type default)
			)
			(layer "F.SilkS")
		)
		(fp_line
			(start -1.1049 -0.724916)
			(end -1.1049 0.724916)
			(stroke
				(width 0.1)
				(type default)
			)
			(layer "F.Fab")
		)
		(fp_line
			(start -1.1049 0.724916)
			(end 1.1049 0.724916)
			(stroke
				(width 0.1)
				(type default)
			)
			(layer "F.Fab")
		)
		(fp_line
			(start 1.1049 -0.724916)
			(end -1.1049 -0.724916)
			(stroke
				(width 0.1)
				(type default)
			)
			(layer "F.Fab")
		)
		(fp_line
			(start 1.1049 0.724916)
			(end 1.1049 -0.724916)
			(stroke
				(width 0.1)
				(type default)
			)
			(layer "F.Fab")
		)
		(pad "1" smd rect
			(at -0.889 0 180)
			(size 1.016 1.27)
			(layers "F.Cu" "F.Mask" "F.Paste")
			(net "SW_P5V_AUX_FLT")
		)
		(pad "2" smd rect
			(at 0.889 0 180)
			(size 1.016 1.27)
			(layers "F.Cu" "F.Mask" "F.Paste")
			(net "GND")
		)
	)
	(footprint ""
		(layer "F.Cu")
		(at 403.142958 -321.002152 90)
		(property "Reference" "R449"
			(at 0 0 90)
			(layer "F.SilkS")
			(hide yes)
			(effects
				(font
					(size 1.27 1.27)
				)
			)
		)
		(property "Value" ""
			(at 0 0 90)
			(layer "F.Fab")
			(effects
				(font
					(size 1.27 1.27)
				)
			)
		)
		(duplicate_pad_numbers_are_jumpers no)
		(fp_line
			(start 0.7874 -0.4064)
			(end 0.7874 0.4064)
			(stroke
				(width 0.1524)
				(type default)
			)
			(layer "F.SilkS")
		)
		(fp_line
			(start -0.7874 -0.4064)
			(end 0.7874 -0.4064)
			(stroke
				(width 0.1524)
				(type default)
			)
			(layer "F.SilkS")
		)
		(fp_line
			(start 0.7874 0.4064)
			(end -0.7874 0.4064)
			(stroke
				(width 0.1524)
				(type default)
			)
			(layer "F.SilkS")
		)
		(fp_line
			(start -0.7874 0.4064)
			(end -0.7874 -0.4064)
			(stroke
				(width 0.1524)
				(type default)
			)
			(layer "F.SilkS")
		)
		(fp_line
			(start -0.12065 -0.305054)
			(end -0.12065 -0.2794)
			(stroke
				(width 0.1)
				(type default)
			)
			(layer "F.Fab")
		)
		(fp_line
			(start -0.67945 -0.305054)
			(end -0.12065 -0.305054)
			(stroke
				(width 0.1)
				(type default)
			)
			(layer "F.Fab")
		)
		(fp_line
			(start 0.67945 -0.3048)
			(end 0.67945 0.3048)
			(stroke
				(width 0.1)
				(type default)
			)
			(layer "F.Fab")
		)
		(fp_line
			(start 0.12065 -0.3048)
			(end 0.67945 -0.3048)
			(stroke
				(width 0.1)
				(type default)
			)
			(layer "F.Fab")
		)
		(fp_line
			(start 0.12065 -0.2794)
			(end 0.12065 -0.3048)
			(stroke
				(width 0.1)
				(type default)
			)
			(layer "F.Fab")
		)
		(fp_line
			(start -0.12065 -0.2794)
			(end 0.12065 -0.2794)
			(stroke
				(width 0.1)
				(type default)
			)
			(layer "F.Fab")
		)
		(fp_line
			(start 0.120396 0.2794)
			(end -0.12065 0.2794)
			(stroke
				(width 0.1)
				(type default)
			)
			(layer "F.Fab")
		)
		(fp_line
			(start -0.12065 0.2794)
			(end -0.12065 0.3048)
			(stroke
				(width 0.1)
				(type default)
			)
			(layer "F.Fab")
		)
		(fp_line
			(start 0.67945 0.3048)
			(end 0.120396 0.3048)
			(stroke
				(width 0.1)
				(type default)
			)
			(layer "F.Fab")
		)
		(fp_line
			(start 0.120396 0.3048)
			(end 0.120396 0.2794)
			(stroke
				(width 0.1)
				(type default)
			)
			(layer "F.Fab")
		)
		(fp_line
			(start -0.12065 0.3048)
			(end -0.67945 0.3048)
			(stroke
				(width 0.1)
				(type default)
			)
			(layer "F.Fab")
		)
		(fp_line
			(start -0.67945 0.3048)
			(end -0.67945 -0.305054)
			(stroke
				(width 0.1)
				(type default)
			)
			(layer "F.Fab")
		)
		(pad "1" smd circle
			(at -0.40005 0 90)
			(size 0 0)
			(layers "F.Cu" "F.Mask" "F.Paste")
			(net "CPU0_SLP_S3_N")
		)
		(pad "2" smd circle
			(at 0.40005 0 90)
			(size 0 0)
			(layers "F.Cu" "F.Mask" "F.Paste")
			(net "PVDD18_S5_P0")
		)
	)
	(footprint ""
		(layer "F.Cu")
		(at 212.0265 -144.201388 -90)
		(property "Reference" "R2530"
			(at 0 0 270)
			(layer "F.SilkS")
			(hide yes)
			(effects
				(font
					(size 1.27 1.27)
				)
			)
		)
		(property "Value" ""
			(at 0 0 270)
			(layer "F.Fab")
			(effects
				(font
					(size 1.27 1.27)
				)
			)
		)
		(duplicate_pad_numbers_are_jumpers no)
		(fp_line
			(start -0.7874 0.4064)
			(end -0.7874 -0.4064)
			(stroke
				(width 0.1524)
				(type default)
			)
			(layer "F.SilkS")
		)
		(fp_line
			(start 0.7874 0.4064)
			(end -0.7874 0.4064)
			(stroke
				(width 0.1524)
				(type default)
			)
			(layer "F.SilkS")
		)
		(fp_line
			(start -0.7874 -0.4064)
			(end 0.7874 -0.4064)
			(stroke
				(width 0.1524)
				(type default)
			)
			(layer "F.SilkS")
		)
		(fp_line
			(start 0.7874 -0.4064)
			(end 0.7874 0.4064)
			(stroke
				(width 0.1524)
				(type default)
			)
			(layer "F.SilkS")
		)
		(fp_line
			(start -0.67945 0.3048)
			(end -0.67945 -0.305054)
			(stroke
				(width 0.1)
				(type default)
			)
			(layer "F.Fab")
		)
		(fp_line
			(start -0.12065 0.3048)
			(end -0.67945 0.3048)
			(stroke
				(width 0.1)
				(type default)
			)
			(layer "F.Fab")
		)
		(fp_line
			(start 0.120396 0.3048)
			(end 0.120396 0.2794)
			(stroke
				(width 0.1)
				(type default)
			)
			(layer "F.Fab")
		)
		(fp_line
			(start 0.67945 0.3048)
			(end 0.120396 0.3048)
			(stroke
				(width 0.1)
				(type default)
			)
			(layer "F.Fab")
		)
		(fp_line
			(start -0.12065 0.2794)
			(end -0.12065 0.3048)
			(stroke
				(width 0.1)
				(type default)
			)
			(layer "F.Fab")
		)
		(fp_line
			(start 0.120396 0.2794)
			(end -0.12065 0.2794)
			(stroke
				(width 0.1)
				(type default)
			)
			(layer "F.Fab")
		)
		(fp_line
			(start -0.12065 -0.2794)
			(end 0.12065 -0.2794)
			(stroke
				(width 0.1)
				(type default)
			)
			(layer "F.Fab")
		)
		(fp_line
			(start 0.12065 -0.2794)
			(end 0.12065 -0.3048)
			(stroke
				(width 0.1)
				(type default)
			)
			(layer "F.Fab")
		)
		(fp_line
			(start 0.12065 -0.3048)
			(end 0.67945 -0.3048)
			(stroke
				(width 0.1)
				(type default)
			)
			(layer "F.Fab")
		)
		(fp_line
			(start 0.67945 -0.3048)
			(end 0.67945 0.3048)
			(stroke
				(width 0.1)
				(type default)
			)
			(layer "F.Fab")
		)
		(fp_line
			(start -0.67945 -0.305054)
			(end -0.12065 -0.305054)
			(stroke
				(width 0.1)
				(type default)
			)
			(layer "F.Fab")
		)
		(fp_line
			(start -0.12065 -0.305054)
			(end -0.12065 -0.2794)
			(stroke
				(width 0.1)
				(type default)
			)
			(layer "F.Fab")
		)
		(pad "1" smd circle
			(at -0.40005 0 270)
			(size 0 0)
			(layers "F.Cu" "F.Mask" "F.Paste")
			(net "P12V_AUX")
		)
		(pad "2" smd circle
			(at 0.40005 0 270)
			(size 0 0)
			(layers "F.Cu" "F.Mask" "F.Paste")
			(net "P12V_AUX_BLEEDING")
		)
	)
	(footprint ""
		(layer "F.Cu")
		(at 200.995534 -118.782084)
		(property "Reference" "R4157"
			(at 0 0 0)
			(layer "F.SilkS")
			(hide yes)
			(effects
				(font
					(size 1.27 1.27)
				)
			)
		)
		(property "Value" ""
			(at 0 0 0)
			(layer "F.Fab")
			(effects
				(font
					(size 1.27 1.27)
				)
			)
		)
		(duplicate_pad_numbers_are_jumpers no)
		(fp_line
			(start -0.7874 -0.4064)
			(end 0.7874 -0.4064)
			(stroke
				(width 0.1524)
				(type default)
			)
			(layer "F.SilkS")
		)
		(fp_line
			(start -0.7874 0.4064)
			(end -0.7874 -0.4064)
			(stroke
				(width 0.1524)
				(type default)
			)
			(layer "F.SilkS")
		)
		(fp_line
			(start 0.7874 -0.4064)
			(end 0.7874 0.4064)
			(stroke
				(width 0.1524)
				(type default)
			)
			(layer "F.SilkS")
		)
		(fp_line
			(start 0.7874 0.4064)
			(end -0.7874 0.4064)
			(stroke
				(width 0.1524)
				(type default)
			)
			(layer "F.SilkS")
		)
		(fp_line
			(start -0.67945 -0.305054)
			(end -0.12065 -0.305054)
			(stroke
				(width 0.1)
				(type default)
			)
			(layer "F.Fab")
		)
		(fp_line
			(start -0.67945 0.3048)
			(end -0.67945 -0.305054)
			(stroke
				(width 0.1)
				(type default)
			)
			(layer "F.Fab")
		)
		(fp_line
			(start -0.12065 -0.305054)
			(end -0.12065 -0.2794)
			(stroke
				(width 0.1)
				(type default)
			)
			(layer "F.Fab")
		)
		(fp_line
			(start -0.12065 -0.2794)
			(end 0.12065 -0.2794)
			(stroke
				(width 0.1)
				(type default)
			)
			(layer "F.Fab")
		)
		(fp_line
			(start -0.12065 0.2794)
			(end -0.12065 0.3048)
			(stroke
				(width 0.1)
				(type default)
			)
			(layer "F.Fab")
		)
		(fp_line
			(start -0.12065 0.3048)
			(end -0.67945 0.3048)
			(stroke
				(width 0.1)
				(type default)
			)
			(layer "F.Fab")
		)
		(fp_line
			(start 0.120396 0.2794)
			(end -0.12065 0.2794)
			(stroke
				(width 0.1)
				(type default)
			)
			(layer "F.Fab")
		)
		(fp_line
			(start 0.120396 0.3048)
			(end 0.120396 0.2794)
			(stroke
				(width 0.1)
				(type default)
			)
			(layer "F.Fab")
		)
		(fp_line
			(start 0.12065 -0.3048)
			(end 0.67945 -0.3048)
			(stroke
				(width 0.1)
				(type default)
			)
			(layer "F.Fab")
		)
		(fp_line
			(start 0.12065 -0.2794)
			(end 0.12065 -0.3048)
			(stroke
				(width 0.1)
				(type default)
			)
			(layer "F.Fab")
		)
		(fp_line
			(start 0.67945 -0.3048)
			(end 0.67945 0.3048)
			(stroke
				(width 0.1)
				(type default)
			)
			(layer "F.Fab")
		)
		(fp_line
			(start 0.67945 0.3048)
			(end 0.120396 0.3048)
			(stroke
				(width 0.1)
				(type default)
			)
			(layer "F.Fab")
		)
		(pad "1" smd circle
			(at -0.40005 0)
			(size 0 0)
			(layers "F.Cu" "F.Mask" "F.Paste")
			(net "PRSNT_CABLE_GPU_A1_ISO_R_N")
		)
		(pad "2" smd circle
			(at 0.40005 0)
			(size 0 0)
			(layers "F.Cu" "F.Mask" "F.Paste")
			(net "PRSNT_CABLE_GPU_A1_ISO_N")
		)
	)
	(footprint ""
		(layer "F.Cu")
		(at 146.03349 -31.18739)
		(property "Reference" "R341"
			(at 0 0 0)
			(layer "F.SilkS")
			(hide yes)
			(effects
				(font
					(size 1.27 1.27)
				)
			)
		)
		(property "Value" ""
			(at 0 0 0)
			(layer "F.Fab")
			(effects
				(font
					(size 1.27 1.27)
				)
			)
		)
		(duplicate_pad_numbers_are_jumpers no)
		(fp_line
			(start -0.7874 -0.4064)
			(end 0.7874 -0.4064)
			(stroke
				(width 0.1524)
				(type default)
			)
			(layer "F.SilkS")
		)
		(fp_line
			(start -0.7874 0.4064)
			(end -0.7874 -0.4064)
			(stroke
				(width 0.1524)
				(type default)
			)
			(layer "F.SilkS")
		)
		(fp_line
			(start 0.7874 -0.4064)
			(end 0.7874 0.4064)
			(stroke
				(width 0.1524)
				(type default)
			)
			(layer "F.SilkS")
		)
		(fp_line
			(start 0.7874 0.4064)
			(end -0.7874 0.4064)
			(stroke
				(width 0.1524)
				(type default)
			)
			(layer "F.SilkS")
		)
		(fp_line
			(start -0.67945 -0.305054)
			(end -0.12065 -0.305054)
			(stroke
				(width 0.1)
				(type default)
			)
			(layer "F.Fab")
		)
		(fp_line
			(start -0.67945 0.3048)
			(end -0.67945 -0.305054)
			(stroke
				(width 0.1)
				(type default)
			)
			(layer "F.Fab")
		)
		(fp_line
			(start -0.12065 -0.305054)
			(end -0.12065 -0.2794)
			(stroke
				(width 0.1)
				(type default)
			)
			(layer "F.Fab")
		)
		(fp_line
			(start -0.12065 -0.2794)
			(end 0.12065 -0.2794)
			(stroke
				(width 0.1)
				(type default)
			)
			(layer "F.Fab")
		)
		(fp_line
			(start -0.12065 0.2794)
			(end -0.12065 0.3048)
			(stroke
				(width 0.1)
				(type default)
			)
			(layer "F.Fab")
		)
		(fp_line
			(start -0.12065 0.3048)
			(end -0.67945 0.3048)
			(stroke
				(width 0.1)
				(type default)
			)
			(layer "F.Fab")
		)
		(fp_line
			(start 0.120396 0.2794)
			(end -0.12065 0.2794)
			(stroke
				(width 0.1)
				(type default)
			)
			(layer "F.Fab")
		)
		(fp_line
			(start 0.120396 0.3048)
			(end 0.120396 0.2794)
			(stroke
				(width 0.1)
				(type default)
			)
			(layer "F.Fab")
		)
		(fp_line
			(start 0.12065 -0.3048)
			(end 0.67945 -0.3048)
			(stroke
				(width 0.1)
				(type default)
			)
			(layer "F.Fab")
		)
		(fp_line
			(start 0.12065 -0.2794)
			(end 0.12065 -0.3048)
			(stroke
				(width 0.1)
				(type default)
			)
			(layer "F.Fab")
		)
		(fp_line
			(start 0.67945 -0.3048)
			(end 0.67945 0.3048)
			(stroke
				(width 0.1)
				(type default)
			)
			(layer "F.Fab")
		)
		(fp_line
			(start 0.67945 0.3048)
			(end 0.120396 0.3048)
			(stroke
				(width 0.1)
				(type default)
			)
			(layer "F.Fab")
		)
		(pad "1" smd rect
			(at -0.40005 0 180)
			(size 0.4572 0.508)
			(layers "F.Cu" "F.Mask" "F.Paste")
			(net "USB3_CPU0_BMC_TX_DP")
		)
		(pad "2" smd rect
			(at 0.40005 0 180)
			(size 0.4572 0.508)
			(layers "F.Cu" "F.Mask" "F.Paste")
			(net "GND")
		)
	)
)
